(kicad_pcb
	(version 20260206)
	(generator "pcbnew")
	(generator_version "10.0")
	(general
		(thickness 1.6)
		(legacy_teardrops no)
	)
	(paper "A4")
	(title_block
		(title "04192023_DAF0TMB3IC0_F0TG_MB_C_brd_V02_OCP.brd")
		(comment 1 "Grand Teton / footprints 5392-5399 of 8354")
	)
	(layers
		(0 "F.Cu" signal "TOP")
		(4 "In1.Cu" signal "GND")
		(6 "In2.Cu" signal "IN1")
		(8 "In3.Cu" signal "GND1")
		(10 "In4.Cu" signal "IN2")
		(12 "In5.Cu" signal "GND2")
		(14 "In6.Cu" signal "IN3")
		(16 "In7.Cu" signal "GND3")
		(18 "In8.Cu" signal "VCC")
		(20 "In9.Cu" signal "VCC1")
		(22 "In10.Cu" signal "GND4")
		(24 "In11.Cu" signal "IN4")
		(26 "In12.Cu" signal "GND5")
		(28 "In13.Cu" signal "IN5")
		(30 "In14.Cu" signal "GND6")
		(32 "In15.Cu" signal "IN6")
		(34 "In16.Cu" signal "GND7")
		(2 "B.Cu" signal "BOTTOM")
		(9 "F.Adhes" user "F.Adhesive")
		(11 "B.Adhes" user "B.Adhesive")
		(13 "F.Paste" user "Package Geometry/Pastemask Top")
		(15 "B.Paste" user "Package Geometry/Pastemask Bottom")
		(5 "F.SilkS" user "Ref Des/Silkscreen Top")
		(7 "B.SilkS" user "Ref Des/Silkscreen Bottom")
		(1 "F.Mask" user "Board Geometry/Soldermask Top")
		(3 "B.Mask" user "Board Geometry/Soldermask Bottom")
		(17 "Dwgs.User" user "User.Drawings")
		(19 "Cmts.User" user "User.Comments")
		(21 "Eco1.User" user "User.Eco1")
		(23 "Eco2.User" user "User.Eco2")
		(25 "Edge.Cuts" user "Board Geometry/Outline")
		(27 "Margin" user)
		(31 "F.CrtYd" user "Package Geometry/Place Bound Top")
		(29 "B.CrtYd" user "Package Geometry/Place Bound Bottom")
		(35 "F.Fab" user "Ref Des/Assembly Top")
		(33 "B.Fab" user "Ref Des/Assembly Bottom")
	)
	(footprint ""
		(layer "B.Cu")
		(at 231.902 -232.156 90)
		(property "Reference" "R139"
			(at 0 0 90)
			(layer "B.SilkS")
			(hide yes)
			(effects
				(font
					(size 1.27 1.27)
				)
				(justify mirror)
			)
		)
		(property "Value" ""
			(at 0 0 90)
			(layer "B.Fab")
			(effects
				(font
					(size 1.27 1.27)
				)
				(justify mirror)
			)
		)
		(duplicate_pad_numbers_are_jumpers no)
		(fp_line
			(start 0.7874 -0.4064)
			(end -0.7874 -0.4064)
			(stroke
				(width 0.1524)
				(type default)
			)
			(layer "B.SilkS")
		)
		(fp_line
			(start -0.7874 -0.4064)
			(end -0.7874 0.4064)
			(stroke
				(width 0.1524)
				(type default)
			)
			(layer "B.SilkS")
		)
		(fp_line
			(start 0.7874 0.4064)
			(end 0.7874 -0.4064)
			(stroke
				(width 0.1524)
				(type default)
			)
			(layer "B.SilkS")
		)
		(fp_line
			(start -0.7874 0.4064)
			(end 0.7874 0.4064)
			(stroke
				(width 0.1524)
				(type default)
			)
			(layer "B.SilkS")
		)
		(fp_line
			(start 0.67945 -0.305054)
			(end 0.12065 -0.305054)
			(stroke
				(width 0.1)
				(type default)
			)
			(layer "B.Fab")
		)
		(fp_line
			(start 0.12065 -0.305054)
			(end 0.12065 -0.2794)
			(stroke
				(width 0.1)
				(type default)
			)
			(layer "B.Fab")
		)
		(fp_line
			(start -0.12065 -0.3048)
			(end -0.67945 -0.3048)
			(stroke
				(width 0.1)
				(type default)
			)
			(layer "B.Fab")
		)
		(fp_line
			(start -0.67945 -0.3048)
			(end -0.67945 0.3048)
			(stroke
				(width 0.1)
				(type default)
			)
			(layer "B.Fab")
		)
		(fp_line
			(start 0.12065 -0.2794)
			(end -0.12065 -0.2794)
			(stroke
				(width 0.1)
				(type default)
			)
			(layer "B.Fab")
		)
		(fp_line
			(start -0.12065 -0.2794)
			(end -0.12065 -0.3048)
			(stroke
				(width 0.1)
				(type default)
			)
			(layer "B.Fab")
		)
		(fp_line
			(start 0.12065 0.2794)
			(end 0.12065 0.3048)
			(stroke
				(width 0.1)
				(type default)
			)
			(layer "B.Fab")
		)
		(fp_line
			(start -0.120396 0.2794)
			(end 0.12065 0.2794)
			(stroke
				(width 0.1)
				(type default)
			)
			(layer "B.Fab")
		)
		(fp_line
			(start 0.67945 0.3048)
			(end 0.67945 -0.305054)
			(stroke
				(width 0.1)
				(type default)
			)
			(layer "B.Fab")
		)
		(fp_line
			(start 0.12065 0.3048)
			(end 0.67945 0.3048)
			(stroke
				(width 0.1)
				(type default)
			)
			(layer "B.Fab")
		)
		(fp_line
			(start -0.120396 0.3048)
			(end -0.120396 0.2794)
			(stroke
				(width 0.1)
				(type default)
			)
			(layer "B.Fab")
		)
		(fp_line
			(start -0.67945 0.3048)
			(end -0.120396 0.3048)
			(stroke
				(width 0.1)
				(type default)
			)
			(layer "B.Fab")
		)
		(pad "1" smd circle
			(at 0.40005 0 270)
			(size 0 0)
			(layers "B.Cu" "B.Mask" "B.Paste")
			(net "I3C_MUX_CPU0_VIO")
		)
		(pad "2" smd circle
			(at -0.40005 0 270)
			(size 0 0)
			(layers "B.Cu" "B.Mask" "B.Paste")
			(net "PVDD18_S5_P0")
		)
	)
	(footprint ""
		(layer "B.Cu")
		(at 405.419052 -398.942052 90)
		(property "Reference" "C967"
			(at 0 0 90)
			(layer "B.SilkS")
			(hide yes)
			(effects
				(font
					(size 1.27 1.27)
				)
				(justify mirror)
			)
		)
		(property "Value" ""
			(at 0 0 90)
			(layer "B.Fab")
			(effects
				(font
					(size 1.27 1.27)
				)
				(justify mirror)
			)
		)
		(duplicate_pad_numbers_are_jumpers no)
		(fp_line
			(start 0.7874 -0.4064)
			(end -0.7874 -0.4064)
			(stroke
				(width 0.1524)
				(type default)
			)
			(layer "B.SilkS")
		)
		(fp_line
			(start -0.7874 -0.4064)
			(end -0.7874 0.4064)
			(stroke
				(width 0.1524)
				(type default)
			)
			(layer "B.SilkS")
		)
		(fp_line
			(start 0.7874 0.4064)
			(end 0.7874 -0.4064)
			(stroke
				(width 0.1524)
				(type default)
			)
			(layer "B.SilkS")
		)
		(fp_line
			(start -0.7874 0.4064)
			(end 0.7874 0.4064)
			(stroke
				(width 0.1524)
				(type default)
			)
			(layer "B.SilkS")
		)
		(fp_line
			(start 0.67945 -0.305054)
			(end 0.12065 -0.305054)
			(stroke
				(width 0.1)
				(type default)
			)
			(layer "B.Fab")
		)
		(fp_line
			(start 0.12065 -0.305054)
			(end 0.12065 -0.2794)
			(stroke
				(width 0.1)
				(type default)
			)
			(layer "B.Fab")
		)
		(fp_line
			(start -0.12065 -0.3048)
			(end -0.67945 -0.3048)
			(stroke
				(width 0.1)
				(type default)
			)
			(layer "B.Fab")
		)
		(fp_line
			(start -0.67945 -0.3048)
			(end -0.67945 0.3048)
			(stroke
				(width 0.1)
				(type default)
			)
			(layer "B.Fab")
		)
		(fp_line
			(start 0.12065 -0.2794)
			(end -0.12065 -0.2794)
			(stroke
				(width 0.1)
				(type default)
			)
			(layer "B.Fab")
		)
		(fp_line
			(start -0.12065 -0.2794)
			(end -0.12065 -0.3048)
			(stroke
				(width 0.1)
				(type default)
			)
			(layer "B.Fab")
		)
		(fp_line
			(start 0.12065 0.2794)
			(end 0.12065 0.3048)
			(stroke
				(width 0.1)
				(type default)
			)
			(layer "B.Fab")
		)
		(fp_line
			(start -0.120396 0.2794)
			(end 0.12065 0.2794)
			(stroke
				(width 0.1)
				(type default)
			)
			(layer "B.Fab")
		)
		(fp_line
			(start 0.67945 0.3048)
			(end 0.67945 -0.305054)
			(stroke
				(width 0.1)
				(type default)
			)
			(layer "B.Fab")
		)
		(fp_line
			(start 0.12065 0.3048)
			(end 0.67945 0.3048)
			(stroke
				(width 0.1)
				(type default)
			)
			(layer "B.Fab")
		)
		(fp_line
			(start -0.120396 0.3048)
			(end -0.120396 0.2794)
			(stroke
				(width 0.1)
				(type default)
			)
			(layer "B.Fab")
		)
		(fp_line
			(start -0.67945 0.3048)
			(end -0.120396 0.3048)
			(stroke
				(width 0.1)
				(type default)
			)
			(layer "B.Fab")
		)
		(pad "1" smd circle
			(at 0.40005 0 270)
			(size 0 0)
			(layers "B.Cu" "B.Mask" "B.Paste")
			(net "P0V9_CPU0_RT2_2A")
		)
		(pad "2" smd circle
			(at -0.40005 0 270)
			(size 0 0)
			(layers "B.Cu" "B.Mask" "B.Paste")
			(net "GND")
		)
	)
	(footprint ""
		(layer "B.Cu")
		(at 125.389386 -250.892564)
		(property "Reference" "C2443"
			(at 0 0 0)
			(layer "B.SilkS")
			(hide yes)
			(effects
				(font
					(size 1.27 1.27)
				)
				(justify mirror)
			)
		)
		(property "Value" ""
			(at 0 0 0)
			(layer "B.Fab")
			(effects
				(font
					(size 1.27 1.27)
				)
				(justify mirror)
			)
		)
		(duplicate_pad_numbers_are_jumpers no)
		(fp_line
			(start -0.7874 -0.4064)
			(end -0.7874 0.4064)
			(stroke
				(width 0.1524)
				(type default)
			)
			(layer "B.SilkS")
		)
		(fp_line
			(start -0.7874 0.4064)
			(end 0.7874 0.4064)
			(stroke
				(width 0.1524)
				(type default)
			)
			(layer "B.SilkS")
		)
		(fp_line
			(start 0.7874 -0.4064)
			(end -0.7874 -0.4064)
			(stroke
				(width 0.1524)
				(type default)
			)
			(layer "B.SilkS")
		)
		(fp_line
			(start 0.7874 0.4064)
			(end 0.7874 -0.4064)
			(stroke
				(width 0.1524)
				(type default)
			)
			(layer "B.SilkS")
		)
		(fp_line
			(start -0.67945 -0.3048)
			(end -0.67945 0.3048)
			(stroke
				(width 0.1)
				(type default)
			)
			(layer "B.Fab")
		)
		(fp_line
			(start -0.67945 0.3048)
			(end -0.120396 0.3048)
			(stroke
				(width 0.1)
				(type default)
			)
			(layer "B.Fab")
		)
		(fp_line
			(start -0.12065 -0.3048)
			(end -0.67945 -0.3048)
			(stroke
				(width 0.1)
				(type default)
			)
			(layer "B.Fab")
		)
		(fp_line
			(start -0.12065 -0.2794)
			(end -0.12065 -0.3048)
			(stroke
				(width 0.1)
				(type default)
			)
			(layer "B.Fab")
		)
		(fp_line
			(start -0.120396 0.2794)
			(end 0.12065 0.2794)
			(stroke
				(width 0.1)
				(type default)
			)
			(layer "B.Fab")
		)
		(fp_line
			(start -0.120396 0.3048)
			(end -0.120396 0.2794)
			(stroke
				(width 0.1)
				(type default)
			)
			(layer "B.Fab")
		)
		(fp_line
			(start 0.12065 -0.305054)
			(end 0.12065 -0.2794)
			(stroke
				(width 0.1)
				(type default)
			)
			(layer "B.Fab")
		)
		(fp_line
			(start 0.12065 -0.2794)
			(end -0.12065 -0.2794)
			(stroke
				(width 0.1)
				(type default)
			)
			(layer "B.Fab")
		)
		(fp_line
			(start 0.12065 0.2794)
			(end 0.12065 0.3048)
			(stroke
				(width 0.1)
				(type default)
			)
			(layer "B.Fab")
		)
		(fp_line
			(start 0.12065 0.3048)
			(end 0.67945 0.3048)
			(stroke
				(width 0.1)
				(type default)
			)
			(layer "B.Fab")
		)
		(fp_line
			(start 0.67945 -0.305054)
			(end 0.12065 -0.305054)
			(stroke
				(width 0.1)
				(type default)
			)
			(layer "B.Fab")
		)
		(fp_line
			(start 0.67945 0.3048)
			(end 0.67945 -0.305054)
			(stroke
				(width 0.1)
				(type default)
			)
			(layer "B.Fab")
		)
		(pad "1" smd circle
			(at 0.40005 0 180)
			(size 0 0)
			(layers "B.Cu" "B.Mask" "B.Paste")
			(net "PVDDCR_SOC_P1")
		)
		(pad "2" smd circle
			(at -0.40005 0 180)
			(size 0 0)
			(layers "B.Cu" "B.Mask" "B.Paste")
			(net "GND")
		)
	)
	(footprint ""
		(layer "B.Cu")
		(at 345.122246 -416.899344 90)
		(property "Reference" "C6560"
			(at 0 0 90)
			(layer "B.SilkS")
			(hide yes)
			(effects
				(font
					(size 1.27 1.27)
				)
				(justify mirror)
			)
		)
		(property "Value" ""
			(at 0 0 90)
			(layer "B.Fab")
			(effects
				(font
					(size 1.27 1.27)
				)
				(justify mirror)
			)
		)
		(duplicate_pad_numbers_are_jumpers no)
		(fp_line
			(start 0.299974 -0.150114)
			(end -0.299974 -0.150114)
			(stroke
				(width 0.1)
				(type default)
			)
			(layer "B.Fab")
		)
		(fp_line
			(start -0.299974 -0.150114)
			(end -0.299974 0.150114)
			(stroke
				(width 0.1)
				(type default)
			)
			(layer "B.Fab")
		)
		(fp_line
			(start 0.299974 0.150114)
			(end 0.299974 -0.150114)
			(stroke
				(width 0.1)
				(type default)
			)
			(layer "B.Fab")
		)
		(fp_line
			(start -0.299974 0.150114)
			(end 0.299974 0.150114)
			(stroke
				(width 0.1)
				(type default)
			)
			(layer "B.Fab")
		)
		(pad "1" smd rect
			(at 0.2667 0 270)
			(size 0.3048 0.381)
			(layers "B.Cu" "B.Mask" "B.Paste")
			(net "P5E_CPU0_P1_TX_BUF_C_DN<13>")
		)
		(pad "2" smd rect
			(at -0.2667 0 270)
			(size 0.3048 0.381)
			(layers "B.Cu" "B.Mask" "B.Paste")
			(net "P5E_CPU0_P1_TX_BUF_DN<13>")
		)
	)
	(footprint ""
		(layer "B.Cu")
		(at 403.006306 -395.148562 90)
		(property "Reference" "C983"
			(at 0 0 90)
			(layer "B.SilkS")
			(hide yes)
			(effects
				(font
					(size 1.27 1.27)
				)
				(justify mirror)
			)
		)
		(property "Value" ""
			(at 0 0 90)
			(layer "B.Fab")
			(effects
				(font
					(size 1.27 1.27)
				)
				(justify mirror)
			)
		)
		(duplicate_pad_numbers_are_jumpers no)
		(fp_line
			(start 0.299974 -0.150114)
			(end -0.299974 -0.150114)
			(stroke
				(width 0.1)
				(type default)
			)
			(layer "B.Fab")
		)
		(fp_line
			(start -0.299974 -0.150114)
			(end -0.299974 0.150114)
			(stroke
				(width 0.1)
				(type default)
			)
			(layer "B.Fab")
		)
		(fp_line
			(start 0.299974 0.150114)
			(end 0.299974 -0.150114)
			(stroke
				(width 0.1)
				(type default)
			)
			(layer "B.Fab")
		)
		(fp_line
			(start -0.299974 0.150114)
			(end 0.299974 0.150114)
			(stroke
				(width 0.1)
				(type default)
			)
			(layer "B.Fab")
		)
		(pad "1" smd rect
			(at 0.2667 0 270)
			(size 0.3048 0.381)
			(layers "B.Cu" "B.Mask" "B.Paste")
			(net "P0V9_CPU0_RT2_2A")
		)
		(pad "2" smd rect
			(at -0.2667 0 270)
			(size 0.3048 0.381)
			(layers "B.Cu" "B.Mask" "B.Paste")
			(net "GND")
		)
	)
	(footprint ""
		(layer "B.Cu")
		(at 328.462386 -398.055084 90)
		(property "Reference" "C632"
			(at 0 0 90)
			(layer "B.SilkS")
			(hide yes)
			(effects
				(font
					(size 1.27 1.27)
				)
				(justify mirror)
			)
		)
		(property "Value" ""
			(at 0 0 90)
			(layer "B.Fab")
			(effects
				(font
					(size 1.27 1.27)
				)
				(justify mirror)
			)
		)
		(duplicate_pad_numbers_are_jumpers no)
		(fp_line
			(start 1.524 -0.762)
			(end -1.524 -0.762)
			(stroke
				(width 0.1524)
				(type default)
			)
			(layer "B.SilkS")
		)
		(fp_line
			(start -1.524 -0.762)
			(end -1.524 0.762)
			(stroke
				(width 0.1524)
				(type default)
			)
			(layer "B.SilkS")
		)
		(fp_line
			(start 1.524 0.762)
			(end 1.524 -0.762)
			(stroke
				(width 0.1524)
				(type default)
			)
			(layer "B.SilkS")
		)
		(fp_line
			(start -1.524 0.762)
			(end 1.524 0.762)
			(stroke
				(width 0.1524)
				(type default)
			)
			(layer "B.SilkS")
		)
		(fp_line
			(start 1.1049 -0.724916)
			(end 1.1049 0.724916)
			(stroke
				(width 0.1)
				(type default)
			)
			(layer "B.Fab")
		)
		(fp_line
			(start -1.1049 -0.724916)
			(end 1.1049 -0.724916)
			(stroke
				(width 0.1)
				(type default)
			)
			(layer "B.Fab")
		)
		(fp_line
			(start 1.1049 0.724916)
			(end -1.1049 0.724916)
			(stroke
				(width 0.1)
				(type default)
			)
			(layer "B.Fab")
		)
		(fp_line
			(start -1.1049 0.724916)
			(end -1.1049 -0.724916)
			(stroke
				(width 0.1)
				(type default)
			)
			(layer "B.Fab")
		)
		(pad "1" smd rect
			(at 0.889 0 90)
			(size 1.016 1.27)
			(layers "B.Cu" "B.Mask" "B.Paste")
			(net "P0V9_CPU0_RT_2D")
		)
		(pad "2" smd rect
			(at -0.889 0 90)
			(size 1.016 1.27)
			(layers "B.Cu" "B.Mask" "B.Paste")
			(net "GND")
		)
	)
	(footprint ""
		(layer "B.Cu")
		(at 335.90611 -395.148562 90)
		(property "Reference" "C660"
			(at 0 0 90)
			(layer "B.SilkS")
			(hide yes)
			(effects
				(font
					(size 1.27 1.27)
				)
				(justify mirror)
			)
		)
		(property "Value" ""
			(at 0 0 90)
			(layer "B.Fab")
			(effects
				(font
					(size 1.27 1.27)
				)
				(justify mirror)
			)
		)
		(duplicate_pad_numbers_are_jumpers no)
		(fp_line
			(start 0.299974 -0.150114)
			(end -0.299974 -0.150114)
			(stroke
				(width 0.1)
				(type default)
			)
			(layer "B.Fab")
		)
		(fp_line
			(start -0.299974 -0.150114)
			(end -0.299974 0.150114)
			(stroke
				(width 0.1)
				(type default)
			)
			(layer "B.Fab")
		)
		(fp_line
			(start 0.299974 0.150114)
			(end 0.299974 -0.150114)
			(stroke
				(width 0.1)
				(type default)
			)
			(layer "B.Fab")
		)
		(fp_line
			(start -0.299974 0.150114)
			(end 0.299974 0.150114)
			(stroke
				(width 0.1)
				(type default)
			)
			(layer "B.Fab")
		)
		(pad "1" smd rect
			(at 0.2667 0 270)
			(size 0.3048 0.381)
			(layers "B.Cu" "B.Mask" "B.Paste")
			(net "P0V9_CPU0_RT1_2A")
		)
		(pad "2" smd rect
			(at -0.2667 0 270)
			(size 0.3048 0.381)
			(layers "B.Cu" "B.Mask" "B.Paste")
			(net "GND")
		)
	)
	(footprint ""
		(layer "B.Cu")
		(at 237.617 -247.269)
		(property "Reference" "R360"
			(at 0 0 0)
			(layer "B.SilkS")
			(hide yes)
			(effects
				(font
					(size 1.27 1.27)
				)
				(justify mirror)
			)
		)
		(property "Value" ""
			(at 0 0 0)
			(layer "B.Fab")
			(effects
				(font
					(size 1.27 1.27)
				)
				(justify mirror)
			)
		)
		(duplicate_pad_numbers_are_jumpers no)
		(fp_line
			(start -0.7874 -0.4064)
			(end -0.7874 0.4064)
			(stroke
				(width 0.1524)
				(type default)
			)
			(layer "B.SilkS")
		)
		(fp_line
			(start -0.7874 0.4064)
			(end 0.7874 0.4064)
			(stroke
				(width 0.1524)
				(type default)
			)
			(layer "B.SilkS")
		)
		(fp_line
			(start 0.7874 -0.4064)
			(end -0.7874 -0.4064)
			(stroke
				(width 0.1524)
				(type default)
			)
			(layer "B.SilkS")
		)
		(fp_line
			(start 0.7874 0.4064)
			(end 0.7874 -0.4064)
			(stroke
				(width 0.1524)
				(type default)
			)
			(layer "B.SilkS")
		)
		(fp_line
			(start -0.67945 -0.3048)
			(end -0.67945 0.3048)
			(stroke
				(width 0.1)
				(type default)
			)
			(layer "B.Fab")
		)
		(fp_line
			(start -0.67945 0.3048)
			(end -0.120396 0.3048)
			(stroke
				(width 0.1)
				(type default)
			)
			(layer "B.Fab")
		)
		(fp_line
			(start -0.12065 -0.3048)
			(end -0.67945 -0.3048)
			(stroke
				(width 0.1)
				(type default)
			)
			(layer "B.Fab")
		)
		(fp_line
			(start -0.12065 -0.2794)
			(end -0.12065 -0.3048)
			(stroke
				(width 0.1)
				(type default)
			)
			(layer "B.Fab")
		)
		(fp_line
			(start -0.120396 0.2794)
			(end 0.12065 0.2794)
			(stroke
				(width 0.1)
				(type default)
			)
			(layer "B.Fab")
		)
		(fp_line
			(start -0.120396 0.3048)
			(end -0.120396 0.2794)
			(stroke
				(width 0.1)
				(type default)
			)
			(layer "B.Fab")
		)
		(fp_line
			(start 0.12065 -0.305054)
			(end 0.12065 -0.2794)
			(stroke
				(width 0.1)
				(type default)
			)
			(layer "B.Fab")
		)
		(fp_line
			(start 0.12065 -0.2794)
			(end -0.12065 -0.2794)
			(stroke
				(width 0.1)
				(type default)
			)
			(layer "B.Fab")
		)
		(fp_line
			(start 0.12065 0.2794)
			(end 0.12065 0.3048)
			(stroke
				(width 0.1)
				(type default)
			)
			(layer "B.Fab")
		)
		(fp_line
			(start 0.12065 0.3048)
			(end 0.67945 0.3048)
			(stroke
				(width 0.1)
				(type default)
			)
			(layer "B.Fab")
		)
		(fp_line
			(start 0.67945 -0.305054)
			(end 0.12065 -0.305054)
			(stroke
				(width 0.1)
				(type default)
			)
			(layer "B.Fab")
		)
		(fp_line
			(start 0.67945 0.3048)
			(end 0.67945 -0.305054)
			(stroke
				(width 0.1)
				(type default)
			)
			(layer "B.Fab")
		)
		(pad "1" smd circle
			(at 0.40005 0 180)
			(size 0 0)
			(layers "B.Cu" "B.Mask" "B.Paste")
			(net "PVDD11_S3_P0")
		)
		(pad "2" smd circle
			(at -0.40005 0 180)
			(size 0 0)
			(layers "B.Cu" "B.Mask" "B.Paste")
			(net "SMB_APML_CPU0_SDA")
		)
	)
)
